(kicad_pcb
	(version 20260206)
	(generator "pcbnew")
	(generator_version "10.0")
	(general
		(thickness 1.6)
		(legacy_teardrops no)
	)
	(paper "A4")
	(title_block
		(title "Wiwynn_Tioga_Pass_MB.brd")
		(comment 1 "Tioga Pass / footprints 3790-3796 of 4770")
	)
	(layers
		(0 "F.Cu" signal "TOP")
		(4 "In1.Cu" signal "L2GND")
		(6 "In2.Cu" signal "L3")
		(8 "In3.Cu" signal "L4GND")
		(10 "In4.Cu" signal "L5")
		(12 "In5.Cu" signal "L6GND")
		(14 "In6.Cu" signal "L7VCC")
		(16 "In7.Cu" signal "L8VCC")
		(18 "In8.Cu" signal "L9GND")
		(20 "In9.Cu" signal "L10")
		(22 "In10.Cu" signal "L11GND")
		(24 "In11.Cu" signal "L12")
		(26 "In12.Cu" signal "L13GND")
		(2 "B.Cu" signal "BOTTOM")
		(9 "F.Adhes" user "F.Adhesive")
		(11 "B.Adhes" user "B.Adhesive")
		(13 "F.Paste" user "Package Geometry/Pastemask Top")
		(15 "B.Paste" user "Package Geometry/Pastemask Bottom")
		(5 "F.SilkS" user "Ref Des/Silkscreen Top")
		(7 "B.SilkS" user "Ref Des/Silkscreen Bottom")
		(1 "F.Mask" user "Board Geometry/Soldermask Top")
		(3 "B.Mask" user "Board Geometry/Soldermask Bottom")
		(17 "Dwgs.User" user "User.Drawings")
		(19 "Cmts.User" user "User.Comments")
		(21 "Eco1.User" user "User.Eco1")
		(23 "Eco2.User" user "User.Eco2")
		(25 "Edge.Cuts" user "Board Geometry/Outline")
		(27 "Margin" user)
		(31 "F.CrtYd" user "Package Geometry/Place Bound Top")
		(29 "B.CrtYd" user "Package Geometry/Place Bound Bottom")
		(35 "F.Fab" user "Ref Des/Assembly Top")
		(33 "B.Fab" user "Ref Des/Assembly Bottom")
	)
	(footprint ""
		(layer "B.Cu")
		(at 163.531042 -71.982076 180)
		(property "Reference" "R6P46"
			(at 0 0 0)
			(layer "B.SilkS")
			(hide yes)
			(effects
				(font
					(size 1.27 1.27)
				)
				(justify mirror)
			)
		)
		(property "Value" ""
			(at 0 0 0)
			(layer "B.Fab")
			(effects
				(font
					(size 1.27 1.27)
				)
				(justify mirror)
			)
		)
		(duplicate_pad_numbers_are_jumpers no)
		(fp_poly
			(pts
				(xy 0.2794 -0.1016) (xy -0.2794 -0.1016) (xy -0.2794 0.9906) (xy 0.2794 0.9906)
			)
			(stroke
				(width 0)
				(type default)
			)
			(fill no)
			(layer "B.CrtYd")
		)
		(fp_line
			(start 0.2794 0.9906)
			(end -0.2794 0.9906)
			(stroke
				(width 0.1)
				(type default)
			)
			(layer "B.Fab")
		)
		(fp_line
			(start 0.2794 -0.1016)
			(end 0.2794 0.9906)
			(stroke
				(width 0.1)
				(type default)
			)
			(layer "B.Fab")
		)
		(fp_line
			(start -0.2794 0.9906)
			(end -0.2794 -0.1016)
			(stroke
				(width 0.1)
				(type default)
			)
			(layer "B.Fab")
		)
		(fp_line
			(start -0.2794 -0.1016)
			(end 0.2794 -0.1016)
			(stroke
				(width 0.1)
				(type default)
			)
			(layer "B.Fab")
		)
		(pad "1" smd rect
			(at 0 0)
			(size 0.508 0.508)
			(layers "B.Cu" "B.Mask" "B.Paste")
			(net "PVCCIO_CPU0")
		)
		(pad "2" smd rect
			(at 0 0.889)
			(size 0.508 0.508)
			(layers "B.Cu" "B.Mask" "B.Paste")
			(net "XDP_CPU_MBP1_N")
		)
		(zone
			(layer "B.Cu")
			(hatch none 0.5)
			(connect_pads
				(clearance 0)
			)
			(min_thickness 0.25)
			(keepout
				(tracks not_allowed)
				(vias allowed)
				(pads allowed)
				(copperpour not_allowed)
				(footprints allowed)
			)
			(placement
				(enabled no)
				(sheetname "")
			)
			(fill
				(thermal_gap 0.5)
				(thermal_bridge_width 0.5)
				(island_removal_mode 0)
			)
			(polygon
				(pts
					(xy 163.277042 -72.617076) (xy 163.785042 -72.617076) (xy 163.785042 -72.236076) (xy 163.277042 -72.236076)
				)
			)
		)
		(zone
			(layer "B.Cu")
			(hatch none 0.5)
			(connect_pads
				(clearance 0)
			)
			(min_thickness 0.25)
			(keepout
				(tracks allowed)
				(vias not_allowed)
				(pads allowed)
				(copperpour not_allowed)
				(footprints allowed)
			)
			(placement
				(enabled no)
				(sheetname "")
			)
			(fill
				(thermal_gap 0.5)
				(thermal_bridge_width 0.5)
				(island_removal_mode 0)
			)
			(polygon
				(pts
					(xy 163.277042 -72.236076) (xy 163.785042 -72.236076) (xy 163.785042 -72.617076) (xy 163.277042 -72.617076)
				)
			)
		)
	)
	(footprint ""
		(layer "B.Cu")
		(at 107.8611 -3.3528 90)
		(property "Reference" "C5G91"
			(at -1.14681 0.76708 180)
			(unlocked yes)
			(layer "B.SilkS")
			(effects
				(font
					(size 0.7874 0.5842)
					(thickness 0.1524)
				)
				(justify mirror)
			)
		)
		(property "Value" ""
			(at 0 0 90)
			(layer "B.Fab")
			(effects
				(font
					(size 1.27 1.27)
				)
				(justify mirror)
			)
		)
		(duplicate_pad_numbers_are_jumpers no)
		(fp_rect
			(start -0.4953 -0.2032)
			(end 0.4953 1.6002)
			(stroke
				(width 0)
				(type default)
			)
			(fill no)
			(layer "B.CrtYd")
		)
		(fp_line
			(start 0.4953 -0.2032)
			(end -0.4953 -0.2032)
			(stroke
				(width 0.1)
				(type default)
			)
			(layer "B.Fab")
		)
		(fp_line
			(start -0.4953 -0.2032)
			(end -0.4953 1.6002)
			(stroke
				(width 0.1)
				(type default)
			)
			(layer "B.Fab")
		)
		(fp_line
			(start 0.4953 1.6002)
			(end 0.4953 -0.2032)
			(stroke
				(width 0.1)
				(type default)
			)
			(layer "B.Fab")
		)
		(fp_line
			(start -0.4953 1.6002)
			(end 0.4953 1.6002)
			(stroke
				(width 0.1)
				(type default)
			)
			(layer "B.Fab")
		)
		(pad "1" smd rect
			(at 0 0 270)
			(size 0.762 0.889)
			(layers "B.Cu" "B.Mask" "B.Paste")
			(net "PVDDQ_GHJ")
		)
		(pad "2" smd rect
			(at 0 1.397 270)
			(size 0.762 0.889)
			(layers "B.Cu" "B.Mask" "B.Paste")
			(net "GND")
		)
		(zone
			(layer "B.Cu")
			(hatch none 0.5)
			(connect_pads
				(clearance 0)
			)
			(min_thickness 0.25)
			(keepout
				(tracks not_allowed)
				(vias allowed)
				(pads allowed)
				(copperpour not_allowed)
				(footprints allowed)
			)
			(placement
				(enabled no)
				(sheetname "")
			)
			(fill
				(thermal_gap 0.5)
				(thermal_bridge_width 0.5)
				(island_removal_mode 0)
			)
			(polygon
				(pts
					(xy 108.3056 -2.9718) (xy 108.8136 -2.9718) (xy 108.8136 -3.7338) (xy 108.3056 -3.7338)
				)
			)
		)
	)
	(footprint ""
		(layer "B.Cu")
		(at 403.01418 -117.6655 180)
		(property "Reference" "C2M25"
			(at 0 0 0)
			(layer "B.SilkS")
			(hide yes)
			(effects
				(font
					(size 1.27 1.27)
				)
				(justify mirror)
			)
		)
		(property "Value" ""
			(at 0 0 0)
			(layer "B.Fab")
			(effects
				(font
					(size 1.27 1.27)
				)
				(justify mirror)
			)
		)
		(duplicate_pad_numbers_are_jumpers no)
		(fp_poly
			(pts
				(xy -0.3048 -0.1016) (xy -0.3048 0.9906) (xy 0.3048 0.9906) (xy 0.3048 -0.1016)
			)
			(stroke
				(width 0)
				(type default)
			)
			(fill no)
			(layer "B.CrtYd")
		)
		(fp_line
			(start 0.3048 0.9906)
			(end -0.3048 0.9906)
			(stroke
				(width 0.1)
				(type default)
			)
			(layer "B.Fab")
		)
		(fp_line
			(start 0.3048 -0.1016)
			(end 0.3048 0.9906)
			(stroke
				(width 0.1)
				(type default)
			)
			(layer "B.Fab")
		)
		(fp_line
			(start -0.3048 0.9906)
			(end -0.3048 -0.1016)
			(stroke
				(width 0.1)
				(type default)
			)
			(layer "B.Fab")
		)
		(fp_line
			(start -0.3048 -0.1016)
			(end 0.3048 -0.1016)
			(stroke
				(width 0.1)
				(type default)
			)
			(layer "B.Fab")
		)
		(pad "1" smd rect
			(at 0 0)
			(size 0.508 0.508)
			(layers "B.Cu" "B.Mask" "B.Paste")
			(net "P1V05_PCH_STBY")
		)
		(pad "2" smd rect
			(at 0 0.889)
			(size 0.508 0.508)
			(layers "B.Cu" "B.Mask" "B.Paste")
			(net "GND")
		)
		(zone
			(layer "B.Cu")
			(hatch none 0.5)
			(connect_pads
				(clearance 0)
			)
			(min_thickness 0.25)
			(keepout
				(tracks not_allowed)
				(vias allowed)
				(pads allowed)
				(copperpour not_allowed)
				(footprints allowed)
			)
			(placement
				(enabled no)
				(sheetname "")
			)
			(fill
				(thermal_gap 0.5)
				(thermal_bridge_width 0.5)
				(island_removal_mode 0)
			)
			(polygon
				(pts
					(xy 402.76018 -118.3005) (xy 403.26818 -118.3005) (xy 403.26818 -117.9195) (xy 402.76018 -117.9195)
				)
			)
		)
		(zone
			(layer "B.Cu")
			(hatch none 0.5)
			(connect_pads
				(clearance 0)
			)
			(min_thickness 0.25)
			(keepout
				(tracks allowed)
				(vias not_allowed)
				(pads allowed)
				(copperpour not_allowed)
				(footprints allowed)
			)
			(placement
				(enabled no)
				(sheetname "")
			)
			(fill
				(thermal_gap 0.5)
				(thermal_bridge_width 0.5)
				(island_removal_mode 0)
			)
			(polygon
				(pts
					(xy 402.76018 -117.9195) (xy 403.26818 -117.9195) (xy 403.26818 -118.3005) (xy 402.76018 -118.3005)
				)
			)
		)
	)
	(footprint ""
		(layer "B.Cu")
		(at 455.200258 -31.237174 -90)
		(property "Reference" "R8D36"
			(at 0 0 90)
			(layer "B.SilkS")
			(hide yes)
			(effects
				(font
					(size 1.27 1.27)
				)
				(justify mirror)
			)
		)
		(property "Value" ""
			(at 0 0 90)
			(layer "B.Fab")
			(effects
				(font
					(size 1.27 1.27)
				)
				(justify mirror)
			)
		)
		(duplicate_pad_numbers_are_jumpers no)
		(fp_poly
			(pts
				(xy 0.2794 -0.1016) (xy -0.2794 -0.1016) (xy -0.2794 0.9906) (xy 0.2794 0.9906)
			)
			(stroke
				(width 0)
				(type default)
			)
			(fill no)
			(layer "B.CrtYd")
		)
		(fp_line
			(start -0.2794 0.9906)
			(end -0.2794 -0.1016)
			(stroke
				(width 0.1)
				(type default)
			)
			(layer "B.Fab")
		)
		(fp_line
			(start 0.2794 0.9906)
			(end -0.2794 0.9906)
			(stroke
				(width 0.1)
				(type default)
			)
			(layer "B.Fab")
		)
		(fp_line
			(start -0.2794 -0.1016)
			(end 0.2794 -0.1016)
			(stroke
				(width 0.1)
				(type default)
			)
			(layer "B.Fab")
		)
		(fp_line
			(start 0.2794 -0.1016)
			(end 0.2794 0.9906)
			(stroke
				(width 0.1)
				(type default)
			)
			(layer "B.Fab")
		)
		(pad "1" smd rect
			(at 0 0 90)
			(size 0.508 0.508)
			(layers "B.Cu" "B.Mask" "B.Paste")
			(net "RST_BMC_SRST_R2_N")
		)
		(pad "2" smd rect
			(at 0 0.889 90)
			(size 0.508 0.508)
			(layers "B.Cu" "B.Mask" "B.Paste")
			(net "RST_BMC_DDR3_BUF_IN_N")
		)
		(zone
			(layer "B.Cu")
			(hatch none 0.5)
			(connect_pads
				(clearance 0)
			)
			(min_thickness 0.25)
			(keepout
				(tracks not_allowed)
				(vias allowed)
				(pads allowed)
				(copperpour not_allowed)
				(footprints allowed)
			)
			(placement
				(enabled no)
				(sheetname "")
			)
			(fill
				(thermal_gap 0.5)
				(thermal_bridge_width 0.5)
				(island_removal_mode 0)
			)
			(polygon
				(pts
					(xy 454.565258 -30.983174) (xy 454.565258 -31.491174) (xy 454.946258 -31.491174) (xy 454.946258 -30.983174)
				)
			)
		)
		(zone
			(layer "B.Cu")
			(hatch none 0.5)
			(connect_pads
				(clearance 0)
			)
			(min_thickness 0.25)
			(keepout
				(tracks allowed)
				(vias not_allowed)
				(pads allowed)
				(copperpour not_allowed)
				(footprints allowed)
			)
			(placement
				(enabled no)
				(sheetname "")
			)
			(fill
				(thermal_gap 0.5)
				(thermal_bridge_width 0.5)
				(island_removal_mode 0)
			)
			(polygon
				(pts
					(xy 454.946258 -30.983174) (xy 454.946258 -31.491174) (xy 454.565258 -31.491174) (xy 454.565258 -30.983174)
				)
			)
		)
	)
	(footprint ""
		(layer "B.Cu")
		(at 416.889184 -75.296014 180)
		(property "Reference" "U1R2"
			(at -0.35433 2.159 270)
			(unlocked yes)
			(layer "B.SilkS")
			(effects
				(font
					(size 0.7874 0.5842)
					(thickness 0.1524)
				)
				(justify left mirror)
			)
		)
		(property "Value" ""
			(at 0 0 0)
			(layer "B.Fab")
			(effects
				(font
					(size 1.27 1.27)
				)
				(justify mirror)
			)
		)
		(duplicate_pad_numbers_are_jumpers no)
		(fp_circle
			(center 0.4699 -0.8382)
			(end 0.3429 -0.8382)
			(stroke
				(width 0.254)
				(type default)
			)
			(fill no)
			(layer "B.SilkS")
		)
		(fp_poly
			(pts
				(xy -0.21463 -0.450088) (xy -1.56337 -0.450088) (xy -1.56337 1.75006) (xy -0.21463 1.75006)
			)
			(stroke
				(width 0)
				(type default)
			)
			(fill no)
			(layer "B.CrtYd")
		)
		(fp_line
			(start -0.21463 1.75006)
			(end -0.21463 -0.450088)
			(stroke
				(width 0.1)
				(type default)
			)
			(layer "B.Fab")
		)
		(fp_line
			(start -0.21463 -0.450088)
			(end -1.56337 -0.450088)
			(stroke
				(width 0.1)
				(type default)
			)
			(layer "B.Fab")
		)
		(fp_line
			(start -1.56337 1.75006)
			(end -0.21463 1.75006)
			(stroke
				(width 0.1)
				(type default)
			)
			(layer "B.Fab")
		)
		(fp_line
			(start -1.56337 -0.450088)
			(end -1.56337 1.75006)
			(stroke
				(width 0.1)
				(type default)
			)
			(layer "B.Fab")
		)
		(fp_circle
			(center 0.4699 -0.8382)
			(end 0.3429 -0.8382)
			(stroke
				(width 0.254)
				(type default)
			)
			(fill no)
			(layer "B.Fab")
		)
		(pad "1" smd rect
			(at 0 0)
			(size 1.016 0.381)
			(layers "B.Cu" "B.Mask" "B.Paste")
			(net "FM_FAST_PROCHOT_EN")
		)
		(pad "2" smd rect
			(at 0 0.649986)
			(size 1.016 0.381)
			(layers "B.Cu" "B.Mask" "B.Paste")
			(net "FM_FAST_PROCHOT_THROTTLE_DLY_N")
		)
		(pad "3" smd rect
			(at 0 1.299972)
			(size 1.016 0.381)
			(layers "B.Cu" "B.Mask" "B.Paste")
			(net "GND")
		)
		(pad "4" smd rect
			(at -1.778 1.299972)
			(size 1.016 0.381)
			(layers "B.Cu" "B.Mask" "B.Paste")
			(net "FM_FAST_PROCHOT_THROTTLE_DLY_BU")
		)
		(pad "5" smd rect
			(at -1.778 0)
			(size 1.016 0.381)
			(layers "B.Cu" "B.Mask" "B.Paste")
			(net "P3V3_STBY")
		)
	)
	(footprint ""
		(layer "B.Cu")
		(at 382.5875 -54.8005)
		(property "Reference" "U8F1"
			(at -1.43002 5.67563 0)
			(unlocked yes)
			(layer "B.SilkS")
			(effects
				(font
					(size 0.7874 0.5842)
					(thickness 0.1524)
				)
				(justify left mirror)
			)
		)
		(property "Value" ""
			(at 0 0 0)
			(layer "B.Fab")
			(effects
				(font
					(size 1.27 1.27)
				)
				(justify mirror)
			)
		)
		(duplicate_pad_numbers_are_jumpers no)
		(fp_line
			(start -3.9243 -0.2794)
			(end -3.9243 4.7244)
			(stroke
				(width 0.1524)
				(type default)
			)
			(layer "B.SilkS")
		)
		(fp_line
			(start -3.9243 4.7244)
			(end -1.5367 4.7244)
			(stroke
				(width 0.1524)
				(type default)
			)
			(layer "B.SilkS")
		)
		(fp_line
			(start -3.1242 -0.2794)
			(end -3.1242 0.7366)
			(stroke
				(width 0.1524)
				(type default)
			)
			(layer "B.SilkS")
		)
		(fp_line
			(start -3.1242 0.7366)
			(end -2.3622 0.7366)
			(stroke
				(width 0.1524)
				(type default)
			)
			(layer "B.SilkS")
		)
		(fp_line
			(start -2.3622 -0.2794)
			(end -3.1242 -0.2794)
			(stroke
				(width 0.1524)
				(type default)
			)
			(layer "B.SilkS")
		)
		(fp_line
			(start -2.3622 0.7366)
			(end -2.3622 -0.2794)
			(stroke
				(width 0.1524)
				(type default)
			)
			(layer "B.SilkS")
		)
		(fp_line
			(start -1.5367 -0.2794)
			(end -3.9243 -0.2794)
			(stroke
				(width 0.1524)
				(type default)
			)
			(layer "B.SilkS")
		)
		(fp_line
			(start -1.5367 4.7244)
			(end -1.5367 -0.2794)
			(stroke
				(width 0.1524)
				(type default)
			)
			(layer "B.SilkS")
		)
		(fp_circle
			(center 1.5494 -0.6604)
			(end 1.7399 -0.6604)
			(stroke
				(width 0.381)
				(type default)
			)
			(fill no)
			(layer "B.SilkS")
		)
		(fp_poly
			(pts
				(xy -0.7366 -0.2794) (xy -4.7244 -0.2794) (xy -4.7244 4.7244) (xy -0.7366 4.7244)
			)
			(stroke
				(width 0)
				(type default)
			)
			(fill no)
			(layer "B.CrtYd")
		)
		(fp_line
			(start -4.7244 -0.2794)
			(end -4.7244 4.7244)
			(stroke
				(width 0.1)
				(type default)
			)
			(layer "B.Fab")
		)
		(fp_line
			(start -4.7244 4.7244)
			(end -0.7366 4.7244)
			(stroke
				(width 0.1)
				(type default)
			)
			(layer "B.Fab")
		)
		(fp_line
			(start -0.7366 -0.2794)
			(end -4.7244 -0.2794)
			(stroke
				(width 0.1)
				(type default)
			)
			(layer "B.Fab")
		)
		(fp_line
			(start -0.7366 4.7244)
			(end -0.7366 -0.2794)
			(stroke
				(width 0.1)
				(type default)
			)
			(layer "B.Fab")
		)
		(fp_circle
			(center 1.5494 -0.6604)
			(end 1.7399 -0.6604)
			(stroke
				(width 0.381)
				(type default)
			)
			(fill no)
			(layer "B.Fab")
		)
		(pad "1" smd rect
			(at 0 0 180)
			(size 2.159 0.381)
			(layers "B.Cu" "B.Mask" "B.Paste")
			(net "FM_BIOS_SPI_BMC_CTRL")
		)
		(pad "2" smd rect
			(at 0 0.635 180)
			(size 2.159 0.381)
			(layers "B.Cu" "B.Mask" "B.Paste")
			(net "SPI_PCH_CLK")
		)
		(pad "3" smd rect
			(at 0 1.27 180)
			(size 2.159 0.381)
			(layers "B.Cu" "B.Mask" "B.Paste")
			(net "SPI_BMC_CLK")
		)
		(pad "4" smd rect
			(at 0 1.905 180)
			(size 2.159 0.381)
			(layers "B.Cu" "B.Mask" "B.Paste")
			(net "SPI_SWITCH_CLK")
		)
		(pad "5" smd rect
			(at 0 2.54 180)
			(size 2.159 0.381)
			(layers "B.Cu" "B.Mask" "B.Paste")
			(net "SPI_PCH_MOSI")
		)
		(pad "6" smd rect
			(at 0 3.175 180)
			(size 2.159 0.381)
			(layers "B.Cu" "B.Mask" "B.Paste")
			(net "SPI_BMC_DO")
		)
		(pad "7" smd rect
			(at 0 3.81 180)
			(size 2.159 0.381)
			(layers "B.Cu" "B.Mask" "B.Paste")
			(net "SPI_SWITCH_MOSI")
		)
		(pad "8" smd rect
			(at 0 4.445 180)
			(size 2.159 0.381)
			(layers "B.Cu" "B.Mask" "B.Paste")
			(net "GND")
		)
		(pad "9" smd rect
			(at -5.461 4.445 180)
			(size 2.159 0.381)
			(layers "B.Cu" "B.Mask" "B.Paste")
			(net "SPI_SWITCH_CS0_N")
		)
		(pad "10" smd rect
			(at -5.461 3.81 180)
			(size 2.159 0.381)
			(layers "B.Cu" "B.Mask" "B.Paste")
			(net "SPI_BMC_CS0_N")
		)
		(pad "11" smd rect
			(at -5.461 3.175 180)
			(size 2.159 0.381)
			(layers "B.Cu" "B.Mask" "B.Paste")
			(net "SPI_PCH_CS0_N")
		)
		(pad "12" smd rect
			(at -5.461 2.54 180)
			(size 2.159 0.381)
			(layers "B.Cu" "B.Mask" "B.Paste")
			(net "SPI_SWITCH_MISO")
		)
		(pad "13" smd rect
			(at -5.461 1.905 180)
			(size 2.159 0.381)
			(layers "B.Cu" "B.Mask" "B.Paste")
			(net "SPI_BMC_DI")
		)
		(pad "14" smd rect
			(at -5.461 1.27 180)
			(size 2.159 0.381)
			(layers "B.Cu" "B.Mask" "B.Paste")
			(net "SPI_PCH_MISO_R")
		)
		(pad "15" smd rect
			(at -5.461 0.635 180)
			(size 2.159 0.381)
			(layers "B.Cu" "B.Mask" "B.Paste")
			(net "GND")
		)
		(pad "16" smd rect
			(at -5.461 0 180)
			(size 2.159 0.381)
			(layers "B.Cu" "B.Mask" "B.Paste")
			(net "P3V3_STBY")
		)
	)
	(footprint ""
		(layer "B.Cu")
		(at 111.809276 -84.401914)
		(property "Reference" "C8W4"
			(at -1.47828 0.78994 90)
			(unlocked yes)
			(layer "B.SilkS")
			(effects
				(font
					(size 0.4064 0.254)
					(thickness 0.1524)
				)
				(justify mirror)
			)
		)
		(property "Value" ""
			(at 0 0 0)
			(layer "B.Fab")
			(effects
				(font
					(size 1.27 1.27)
				)
				(justify mirror)
			)
		)
		(duplicate_pad_numbers_are_jumpers no)
		(fp_poly
			(pts
				(xy 0.7239 -0.2159) (xy -0.7239 -0.2159) (xy -0.7239 1.9939) (xy 0.7239 1.9939)
			)
			(stroke
				(width 0)
				(type default)
			)
			(fill no)
			(layer "B.CrtYd")
		)
		(fp_line
			(start -0.7239 -0.2159)
			(end 0.7239 -0.2159)
			(stroke
				(width 0.1)
				(type default)
			)
			(layer "B.Fab")
		)
		(fp_line
			(start -0.7239 1.9939)
			(end -0.7239 -0.2159)
			(stroke
				(width 0.1)
				(type default)
			)
			(layer "B.Fab")
		)
		(fp_line
			(start 0.7239 -0.2159)
			(end 0.7239 1.9939)
			(stroke
				(width 0.1)
				(type default)
			)
			(layer "B.Fab")
		)
		(fp_line
			(start 0.7239 1.9939)
			(end -0.7239 1.9939)
			(stroke
				(width 0.1)
				(type default)
			)
			(layer "B.Fab")
		)
		(pad "1" smd rect
			(at 0 0 180)
			(size 1.27 1.016)
			(layers "B.Cu" "B.Mask" "B.Paste")
			(net "PVCCIN_CPU1")
		)
		(pad "2" smd rect
			(at 0 1.778 180)
			(size 1.27 1.016)
			(layers "B.Cu" "B.Mask" "B.Paste")
			(net "GND")
		)
		(zone
			(layer "B.Cu")
			(hatch none 0.5)
			(connect_pads
				(clearance 0)
			)
			(min_thickness 0.25)
			(keepout
				(tracks not_allowed)
				(vias allowed)
				(pads allowed)
				(copperpour not_allowed)
				(footprints allowed)
			)
			(placement
				(enabled no)
				(sheetname "")
			)
			(fill
				(thermal_gap 0.5)
				(thermal_bridge_width 0.5)
				(island_removal_mode 0)
			)
			(polygon
				(pts
					(xy 112.444276 -83.893914) (xy 111.174276 -83.893914) (xy 111.174276 -83.131914) (xy 112.444276 -83.131914)
				)
			)
		)
	)
)
